(kicad_pcb
	(version 20260206)
	(generator "pcbnew")
	(generator_version "10.0")
	(general
		(thickness 1.6)
		(legacy_teardrops no)
	)
	(paper "A4")
	(title_block
		(title "Bryce Canyon_R.DPB_16317-1_OCP.brd")
		(comment 1 "Bryce Canyon / footprints 1369-1375 of 2099")
	)
	(layers
		(0 "F.Cu" signal "TOP")
		(4 "In1.Cu" signal "L2GND")
		(6 "In2.Cu" signal "L3")
		(8 "In3.Cu" signal "L4VCC")
		(10 "In4.Cu" signal "L5VCC")
		(12 "In5.Cu" signal "L6")
		(14 "In6.Cu" signal "L7GND")
		(2 "B.Cu" signal "BOTTOM")
		(9 "F.Adhes" user "F.Adhesive")
		(11 "B.Adhes" user "B.Adhesive")
		(13 "F.Paste" user "Package Geometry/Pastemask Top")
		(15 "B.Paste" user "Package Geometry/Pastemask Bottom")
		(5 "F.SilkS" user "Ref Des/Silkscreen Top")
		(7 "B.SilkS" user "Ref Des/Silkscreen Bottom")
		(1 "F.Mask" user "Board Geometry/Soldermask Top")
		(3 "B.Mask" user "Board Geometry/Soldermask Bottom")
		(17 "Dwgs.User" user "User.Drawings")
		(19 "Cmts.User" user "User.Comments")
		(21 "Eco1.User" user "User.Eco1")
		(23 "Eco2.User" user "User.Eco2")
		(25 "Edge.Cuts" user "Board Geometry/Outline")
		(27 "Margin" user)
		(31 "F.CrtYd" user "Package Geometry/Place Bound Top")
		(29 "B.CrtYd" user "Package Geometry/Place Bound Bottom")
		(35 "F.Fab" user "Ref Des/Assembly Top")
		(33 "B.Fab" user "Ref Des/Assembly Bottom")
	)
	(footprint ""
		(layer "F.Cu")
		(at 64.013334 -14.660626 90)
		(property "Reference" "C354"
			(at 0 0 90)
			(layer "F.SilkS")
			(hide yes)
			(effects
				(font
					(size 1.27 1.27)
				)
			)
		)
		(property "Value" "SCD01U16V1KX-GP"
			(at -2.8321 -1.7399 90)
			(unlocked yes)
			(layer "F.Fab")
			(hide yes)
			(effects
				(font
					(size 1.016 1.016)
					(thickness 0.1524)
				)
			)
		)
		(property "Device Type" "C0201H13"
			(at -2.8321 -3.2639 90)
			(unlocked yes)
			(layer "F.Fab")
			(hide yes)
			(effects
				(font
					(size 1.016 1.016)
					(thickness 0.1524)
				)
			)
		)
		(duplicate_pad_numbers_are_jumpers no)
		(fp_rect
			(start -0.2794 0.6477)
			(end 0.2794 -0.6477)
			(stroke
				(width 0)
				(type default)
			)
			(fill no)
			(layer "F.CrtYd")
		)
		(fp_rect
			(start -0.2794 0.6477)
			(end 0.2794 -0.6477)
			(stroke
				(width 0)
				(type default)
			)
			(fill no)
			(layer "F.Fab")
		)
		(pad "1" smd custom
			(at 0 -0.2794 90)
			(size 0.0762 0.0762)
			(layers "F.Cu" "F.Mask" "F.Paste")
			(net "SAS_HDD_RX_P25")
			(options
				(clearance outline)
				(anchor circle)
			)
			(primitives
				(gr_poly
					(pts
						(arc
							(start 0.1524 -0.127)
							(mid 0.137521 -0.162921)
							(end 0.1016 -0.1778)
						)
						(arc
							(start -0.1016 -0.1778)
							(mid -0.137521 -0.162921)
							(end -0.1524 -0.127)
						)
						(arc
							(start -0.1524 0.127)
							(mid -0.137521 0.162921)
							(end -0.1016 0.1778)
						)
						(arc
							(start 0.1016 0.1778)
							(mid 0.137521 0.162921)
							(end 0.1524 0.127)
						)
					)
					(width 0)
					(fill yes)
				)
			)
		)
		(pad "2" smd custom
			(at 0 0.2794 90)
			(size 0.0762 0.0762)
			(layers "F.Cu" "F.Mask" "F.Paste")
			(net "PHY_SCC_B_TO_DRV_B_25_DP")
			(options
				(clearance outline)
				(anchor circle)
			)
			(primitives
				(gr_poly
					(pts
						(arc
							(start 0.1524 -0.127)
							(mid 0.137521 -0.162921)
							(end 0.1016 -0.1778)
						)
						(arc
							(start -0.1016 -0.1778)
							(mid -0.137521 -0.162921)
							(end -0.1524 -0.127)
						)
						(arc
							(start -0.1524 0.127)
							(mid -0.137521 0.162921)
							(end -0.1016 0.1778)
						)
						(arc
							(start 0.1016 0.1778)
							(mid 0.137521 0.162921)
							(end 0.1524 0.127)
						)
					)
					(width 0)
					(fill yes)
				)
			)
		)
	)
	(footprint ""
		(layer "F.Cu")
		(at 433.324 -28.829 90)
		(property "Reference" "C468"
			(at 0 0 90)
			(layer "F.SilkS")
			(hide yes)
			(effects
				(font
					(size 1.27 1.27)
				)
			)
		)
		(property "Value" "SCD033U25V2KX-GP"
			(at 1.1811 -2.7051 90)
			(unlocked yes)
			(layer "F.Fab")
			(hide yes)
			(effects
				(font
					(size 1.016 1.016)
					(thickness 0.1524)
				)
			)
		)
		(property "Device Type" "C402H22"
			(at 1.1811 -4.2291 90)
			(unlocked yes)
			(layer "F.Fab")
			(hide yes)
			(effects
				(font
					(size 1.016 1.016)
					(thickness 0.1524)
				)
			)
		)
		(duplicate_pad_numbers_are_jumpers no)
		(fp_rect
			(start -0.4318 0.9525)
			(end 0.4318 -0.9525)
			(stroke
				(width 0)
				(type default)
			)
			(fill no)
			(layer "F.CrtYd")
		)
		(fp_rect
			(start -0.4318 0.9525)
			(end 0.4318 -0.9525)
			(stroke
				(width 0)
				(type default)
			)
			(fill no)
			(layer "F.Fab")
		)
		(pad "1" smd custom
			(at 0 -0.4445 90)
			(size 0.1524 0.1524)
			(layers "F.Cu" "F.Mask" "F.Paste")
			(net "P12V_B")
			(options
				(clearance outline)
				(anchor circle)
			)
			(primitives
				(gr_poly
					(pts
						(arc
							(start 0.3048 -0.2032)
							(mid 0.275042 -0.275042)
							(end 0.2032 -0.3048)
						)
						(arc
							(start -0.2032 -0.3048)
							(mid -0.275042 -0.275042)
							(end -0.3048 -0.2032)
						)
						(arc
							(start -0.3048 0.2032)
							(mid -0.275042 0.275042)
							(end -0.2032 0.3048)
						)
						(arc
							(start 0.2032 0.3048)
							(mid 0.275042 0.275042)
							(end 0.3048 0.2032)
						)
					)
					(width 0)
					(fill yes)
				)
			)
		)
		(pad "2" smd custom
			(at 0 0.4445 90)
			(size 0.1524 0.1524)
			(layers "F.Cu" "F.Mask" "F.Paste")
			(net "SW_HDD_N33")
			(options
				(clearance outline)
				(anchor circle)
			)
			(primitives
				(gr_poly
					(pts
						(arc
							(start 0.3048 -0.2032)
							(mid 0.275042 -0.275042)
							(end 0.2032 -0.3048)
						)
						(arc
							(start -0.2032 -0.3048)
							(mid -0.275042 -0.275042)
							(end -0.3048 -0.2032)
						)
						(arc
							(start -0.3048 0.2032)
							(mid -0.275042 0.275042)
							(end -0.2032 0.3048)
						)
						(arc
							(start 0.2032 0.3048)
							(mid 0.275042 0.275042)
							(end 0.3048 0.2032)
						)
					)
					(width 0)
					(fill yes)
				)
			)
		)
	)
	(footprint ""
		(layer "F.Cu")
		(at 158.663386 -244.660674 90)
		(property "Reference" "C80"
			(at 0 0 90)
			(layer "F.SilkS")
			(hide yes)
			(effects
				(font
					(size 1.27 1.27)
				)
			)
		)
		(property "Value" "SCD01U16V1KX-GP"
			(at -2.8321 -1.7399 90)
			(unlocked yes)
			(layer "F.Fab")
			(hide yes)
			(effects
				(font
					(size 1.016 1.016)
					(thickness 0.1524)
				)
			)
		)
		(property "Device Type" "C0201H13"
			(at -2.8321 -3.2639 90)
			(unlocked yes)
			(layer "F.Fab")
			(hide yes)
			(effects
				(font
					(size 1.016 1.016)
					(thickness 0.1524)
				)
			)
		)
		(duplicate_pad_numbers_are_jumpers no)
		(fp_rect
			(start -0.2794 0.6477)
			(end 0.2794 -0.6477)
			(stroke
				(width 0)
				(type default)
			)
			(fill no)
			(layer "F.CrtYd")
		)
		(fp_rect
			(start -0.2794 0.6477)
			(end 0.2794 -0.6477)
			(stroke
				(width 0)
				(type default)
			)
			(fill no)
			(layer "F.Fab")
		)
		(pad "1" smd custom
			(at 0 -0.2794 90)
			(size 0.0762 0.0762)
			(layers "F.Cu" "F.Mask" "F.Paste")
			(net "SAS_HDD_RX_P4")
			(options
				(clearance outline)
				(anchor circle)
			)
			(primitives
				(gr_poly
					(pts
						(arc
							(start 0.1524 -0.127)
							(mid 0.137521 -0.162921)
							(end 0.1016 -0.1778)
						)
						(arc
							(start -0.1016 -0.1778)
							(mid -0.137521 -0.162921)
							(end -0.1524 -0.127)
						)
						(arc
							(start -0.1524 0.127)
							(mid -0.137521 0.162921)
							(end -0.1016 0.1778)
						)
						(arc
							(start 0.1016 0.1778)
							(mid 0.137521 0.162921)
							(end 0.1524 0.127)
						)
					)
					(width 0)
					(fill yes)
				)
			)
		)
		(pad "2" smd custom
			(at 0 0.2794 90)
			(size 0.0762 0.0762)
			(layers "F.Cu" "F.Mask" "F.Paste")
			(net "PHY_SCC_B_TO_DRV_B_4_DP")
			(options
				(clearance outline)
				(anchor circle)
			)
			(primitives
				(gr_poly
					(pts
						(arc
							(start 0.1524 -0.127)
							(mid 0.137521 -0.162921)
							(end 0.1016 -0.1778)
						)
						(arc
							(start -0.1016 -0.1778)
							(mid -0.137521 -0.162921)
							(end -0.1524 -0.127)
						)
						(arc
							(start -0.1524 0.127)
							(mid -0.137521 0.162921)
							(end -0.1016 0.1778)
						)
						(arc
							(start 0.1016 0.1778)
							(mid 0.137521 0.162921)
							(end 0.1524 0.127)
						)
					)
					(width 0)
					(fill yes)
				)
			)
		)
	)
	(footprint ""
		(layer "F.Cu")
		(at 363.601 -243.586)
		(property "Reference" "R279"
			(at 0 0 0)
			(layer "F.SilkS")
			(hide yes)
			(effects
				(font
					(size 1.27 1.27)
				)
			)
		)
		(property "Value" "4K7R2F-GP"
			(at 0.064008 -3.993896 0)
			(unlocked yes)
			(layer "F.Fab")
			(hide yes)
			(effects
				(font
					(size 1.016 1.016)
					(thickness 0.1524)
				)
			)
		)
		(property "Device Type" "R402H16"
			(at 0.064008 -5.517896 0)
			(unlocked yes)
			(layer "F.Fab")
			(hide yes)
			(effects
				(font
					(size 1.016 1.016)
					(thickness 0.1524)
				)
			)
		)
		(duplicate_pad_numbers_are_jumpers no)
		(fp_line
			(start -0.508 -0.9398)
			(end -0.508 0.9398)
			(stroke
				(width 0.1524)
				(type default)
			)
			(layer "F.SilkS")
		)
		(fp_line
			(start 0.508 -0.9398)
			(end -0.508 -0.9398)
			(stroke
				(width 0.1524)
				(type default)
			)
			(layer "F.SilkS")
		)
		(fp_rect
			(start -0.508 0.9398)
			(end 0.508 -0.9398)
			(stroke
				(width 0)
				(type default)
			)
			(fill no)
			(layer "F.CrtYd")
		)
		(fp_rect
			(start -0.508 0.9398)
			(end 0.508 -0.9398)
			(stroke
				(width 0)
				(type default)
			)
			(fill no)
			(layer "F.Fab")
		)
		(pad "1" smd custom
			(at 0 -0.4445)
			(size 0.1397 0.1397)
			(layers "F.Cu" "F.Mask" "F.Paste")
			(net "SW_PWR_R_HDD7")
			(options
				(clearance outline)
				(anchor circle)
			)
			(primitives
				(gr_poly
					(pts
						(arc
							(start -0.1778 -0.2794)
							(mid -0.249642 -0.249642)
							(end -0.2794 -0.1778)
						)
						(arc
							(start -0.2794 0.1778)
							(mid -0.249642 0.249642)
							(end -0.1778 0.2794)
						)
						(arc
							(start 0.1778 0.2794)
							(mid 0.249642 0.249642)
							(end 0.2794 0.1778)
						)
						(arc
							(start 0.2794 -0.1778)
							(mid 0.249642 -0.249642)
							(end 0.1778 -0.2794)
						)
					)
					(width 0)
					(fill yes)
				)
			)
		)
		(pad "2" smd custom
			(at 0 0.4445)
			(size 0.1397 0.1397)
			(layers "F.Cu" "F.Mask" "F.Paste")
			(net "GND")
			(options
				(clearance outline)
				(anchor circle)
			)
			(primitives
				(gr_poly
					(pts
						(arc
							(start -0.1778 -0.2794)
							(mid -0.249642 -0.249642)
							(end -0.2794 -0.1778)
						)
						(arc
							(start -0.2794 0.1778)
							(mid -0.249642 0.249642)
							(end -0.1778 0.2794)
						)
						(arc
							(start 0.1778 0.2794)
							(mid 0.249642 0.249642)
							(end 0.2794 0.1778)
						)
						(arc
							(start 0.2794 -0.1778)
							(mid 0.249642 -0.249642)
							(end 0.1778 -0.2794)
						)
					)
					(width 0)
					(fill yes)
				)
			)
		)
	)
	(footprint ""
		(layer "F.Cu")
		(at 261.552436 -353.474528 -90)
		(property "Reference" "C566"
			(at 0 0 270)
			(layer "F.SilkS")
			(hide yes)
			(effects
				(font
					(size 1.27 1.27)
				)
			)
		)
		(property "Value" "SCD033U50V3KX-1GP"
			(at 0 -2.8194 270)
			(unlocked yes)
			(layer "F.Fab")
			(hide yes)
			(effects
				(font
					(size 1.016 1.016)
					(thickness 0.1524)
				)
			)
		)
		(property "Device Type" "C603H36"
			(at 0 -4.3434 270)
			(unlocked yes)
			(layer "F.Fab")
			(hide yes)
			(effects
				(font
					(size 1.016 1.016)
					(thickness 0.1524)
				)
			)
		)
		(duplicate_pad_numbers_are_jumpers no)
		(fp_line
			(start 0.508 0)
			(end -0.508 0)
			(stroke
				(width 0.2032)
				(type default)
			)
			(layer "F.SilkS")
		)
		(fp_rect
			(start -0.5842 1.3335)
			(end 0.5842 -1.3335)
			(stroke
				(width 0)
				(type default)
			)
			(fill no)
			(layer "F.CrtYd")
		)
		(fp_rect
			(start -0.5842 1.3335)
			(end 0.5842 -1.3335)
			(stroke
				(width 0)
				(type default)
			)
			(fill no)
			(layer "F.Fab")
		)
		(pad "1" smd custom
			(at 0 -0.762 270)
			(size 0.2159 0.2159)
			(layers "F.Cu" "F.Mask" "F.Paste")
			(net "MB3_CM_GATE_C")
			(options
				(clearance outline)
				(anchor circle)
			)
			(primitives
				(gr_poly
					(pts
						(arc
							(start -0.3302 -0.4318)
							(mid -0.402042 -0.402042)
							(end -0.4318 -0.3302)
						)
						(arc
							(start -0.4318 0.3302)
							(mid -0.402042 0.402042)
							(end -0.3302 0.4318)
						)
						(arc
							(start 0.3302 0.4318)
							(mid 0.402042 0.402042)
							(end 0.4318 0.3302)
						)
						(arc
							(start 0.4318 -0.3302)
							(mid 0.402042 -0.402042)
							(end 0.3302 -0.4318)
						)
					)
					(width 0)
					(fill yes)
				)
			)
		)
		(pad "2" smd custom
			(at 0 0.762 270)
			(size 0.2159 0.2159)
			(layers "F.Cu" "F.Mask" "F.Paste")
			(net "GND")
			(options
				(clearance outline)
				(anchor circle)
			)
			(primitives
				(gr_poly
					(pts
						(arc
							(start -0.3302 -0.4318)
							(mid -0.402042 -0.402042)
							(end -0.4318 -0.3302)
						)
						(arc
							(start -0.4318 0.3302)
							(mid -0.402042 0.402042)
							(end -0.3302 0.4318)
						)
						(arc
							(start 0.3302 0.4318)
							(mid 0.402042 0.402042)
							(end 0.4318 0.3302)
						)
						(arc
							(start 0.4318 -0.3302)
							(mid 0.402042 -0.402042)
							(end 0.3302 -0.4318)
						)
					)
					(width 0)
					(fill yes)
				)
			)
		)
	)
	(footprint ""
		(layer "F.Cu")
		(at 444.4238 -32.7406 180)
		(property "Reference" "R856"
			(at 0 0 180)
			(layer "F.SilkS")
			(hide yes)
			(effects
				(font
					(size 1.27 1.27)
				)
			)
		)
		(property "Value" "220R3F-1-GP"
			(at -0.0254 -2.5146 180)
			(unlocked yes)
			(layer "F.Fab")
			(hide yes)
			(effects
				(font
					(size 1.016 1.016)
					(thickness 0.1524)
				)
			)
		)
		(property "Device Type" "R603H22"
			(at -0.0254 -4.0386 180)
			(unlocked yes)
			(layer "F.Fab")
			(hide yes)
			(effects
				(font
					(size 1.016 1.016)
					(thickness 0.1524)
				)
			)
		)
		(duplicate_pad_numbers_are_jumpers no)
		(fp_line
			(start 0.2032 0)
			(end 0.4826 0)
			(stroke
				(width 0.2032)
				(type default)
			)
			(layer "F.SilkS")
		)
		(fp_line
			(start -0.4826 0)
			(end -0.2032 0)
			(stroke
				(width 0.2032)
				(type default)
			)
			(layer "F.SilkS")
		)
		(fp_rect
			(start -0.5842 1.3335)
			(end 0.5842 -1.3335)
			(stroke
				(width 0)
				(type default)
			)
			(fill no)
			(layer "F.CrtYd")
		)
		(fp_rect
			(start -0.5842 1.3335)
			(end 0.5842 -1.3335)
			(stroke
				(width 0)
				(type default)
			)
			(fill no)
			(layer "F.Fab")
		)
		(pad "1" smd custom
			(at 0 -0.762 180)
			(size 0.2159 0.2159)
			(layers "F.Cu" "F.Mask" "F.Paste")
			(net "HDD_PRSNT_34")
			(options
				(clearance outline)
				(anchor circle)
			)
			(primitives
				(gr_poly
					(pts
						(arc
							(start -0.3302 -0.4318)
							(mid -0.402042 -0.402042)
							(end -0.4318 -0.3302)
						)
						(arc
							(start -0.4318 0.3302)
							(mid -0.402042 0.402042)
							(end -0.3302 0.4318)
						)
						(arc
							(start 0.3302 0.4318)
							(mid 0.402042 0.402042)
							(end 0.4318 0.3302)
						)
						(arc
							(start 0.4318 -0.3302)
							(mid 0.402042 -0.402042)
							(end 0.3302 -0.4318)
						)
					)
					(width 0)
					(fill yes)
				)
			)
		)
		(pad "2" smd custom
			(at 0 0.762 180)
			(size 0.2159 0.2159)
			(layers "F.Cu" "F.Mask" "F.Paste")
			(net "DRIVE_B_34_INS")
			(options
				(clearance outline)
				(anchor circle)
			)
			(primitives
				(gr_poly
					(pts
						(arc
							(start -0.3302 -0.4318)
							(mid -0.402042 -0.402042)
							(end -0.4318 -0.3302)
						)
						(arc
							(start -0.4318 0.3302)
							(mid -0.402042 0.402042)
							(end -0.3302 0.4318)
						)
						(arc
							(start 0.3302 0.4318)
							(mid 0.402042 0.402042)
							(end 0.4318 0.3302)
						)
						(arc
							(start 0.4318 -0.3302)
							(mid 0.402042 -0.402042)
							(end 0.3302 -0.4318)
						)
					)
					(width 0)
					(fill yes)
				)
			)
		)
	)
	(footprint ""
		(layer "F.Cu")
		(at 221.73946 -166.41826 90)
		(property "Reference" "R59"
			(at 0 0 90)
			(layer "F.SilkS")
			(hide yes)
			(effects
				(font
					(size 1.27 1.27)
				)
			)
		)
		(property "Value" "4K7R2F-GP"
			(at 0.064008 -3.993896 90)
			(unlocked yes)
			(layer "F.Fab")
			(hide yes)
			(effects
				(font
					(size 1.016 1.016)
					(thickness 0.1524)
				)
			)
		)
		(property "Device Type" "R402H16"
			(at 0.064008 -5.517896 90)
			(unlocked yes)
			(layer "F.Fab")
			(hide yes)
			(effects
				(font
					(size 1.016 1.016)
					(thickness 0.1524)
				)
			)
		)
		(duplicate_pad_numbers_are_jumpers no)
		(fp_line
			(start 0.508 -0.9398)
			(end -0.508 -0.9398)
			(stroke
				(width 0.1524)
				(type default)
			)
			(layer "F.SilkS")
		)
		(fp_line
			(start -0.508 -0.9398)
			(end -0.508 0.9398)
			(stroke
				(width 0.1524)
				(type default)
			)
			(layer "F.SilkS")
		)
		(fp_rect
			(start -0.508 0.9398)
			(end 0.508 -0.9398)
			(stroke
				(width 0)
				(type default)
			)
			(fill no)
			(layer "F.CrtYd")
		)
		(fp_rect
			(start -0.508 0.9398)
			(end 0.508 -0.9398)
			(stroke
				(width 0)
				(type default)
			)
			(fill no)
			(layer "F.Fab")
		)
		(pad "1" smd custom
			(at 0 -0.4445 90)
			(size 0.1397 0.1397)
			(layers "F.Cu" "F.Mask" "F.Paste")
			(net "IO_EXP6_A2")
			(options
				(clearance outline)
				(anchor circle)
			)
			(primitives
				(gr_poly
					(pts
						(arc
							(start -0.1778 -0.2794)
							(mid -0.249642 -0.249642)
							(end -0.2794 -0.1778)
						)
						(arc
							(start -0.2794 0.1778)
							(mid -0.249642 0.249642)
							(end -0.1778 0.2794)
						)
						(arc
							(start 0.1778 0.2794)
							(mid 0.249642 0.249642)
							(end 0.2794 0.1778)
						)
						(arc
							(start 0.2794 -0.1778)
							(mid 0.249642 -0.249642)
							(end 0.1778 -0.2794)
						)
					)
					(width 0)
					(fill yes)
				)
			)
		)
		(pad "2" smd custom
			(at 0 0.4445 90)
			(size 0.1397 0.1397)
			(layers "F.Cu" "F.Mask" "F.Paste")
			(net "GND")
			(options
				(clearance outline)
				(anchor circle)
			)
			(primitives
				(gr_poly
					(pts
						(arc
							(start -0.1778 -0.2794)
							(mid -0.249642 -0.249642)
							(end -0.2794 -0.1778)
						)
						(arc
							(start -0.2794 0.1778)
							(mid -0.249642 0.249642)
							(end -0.1778 0.2794)
						)
						(arc
							(start 0.1778 0.2794)
							(mid 0.249642 0.249642)
							(end 0.2794 0.1778)
						)
						(arc
							(start 0.2794 -0.1778)
							(mid 0.249642 -0.249642)
							(end 0.1778 -0.2794)
						)
					)
					(width 0)
					(fill yes)
				)
			)
		)
	)
)
